(kicad_pcb
	(version 20211014)
	(generator pcbnew)
	(general
    (thickness 1.6)
  )
	(paper "A4")
	(title_block
    (title "SA800U (Snapdragon 845) Baseboard")
    (date "2023-10-19")
    (rev "1.0.3")
    (company "Antmicro Ltd.")
    (comment 1 "www.antmicro.com")
		(comment 9 "footprints 14-23 of 589")
	)
	(layers
    (0 "F.Cu" signal)
    (1 "In1.Cu" power)
    (2 "In2.Cu" signal)
    (3 "In3.Cu" signal)
    (4 "In4.Cu" power)
    (31 "B.Cu" signal)
    (32 "B.Adhes" user "B.Adhesive")
    (33 "F.Adhes" user "F.Adhesive")
    (34 "B.Paste" user)
    (35 "F.Paste" user)
    (36 "B.SilkS" user "B.Silkscreen")
    (37 "F.SilkS" user "F.Silkscreen")
    (38 "B.Mask" user)
    (39 "F.Mask" user)
    (40 "Dwgs.User" user "User.Drawings")
    (41 "Cmts.User" user "User.Comments")
    (42 "Eco1.User" user "User.Eco1")
    (43 "Eco2.User" user "User.Eco2")
    (44 "Edge.Cuts" user)
    (45 "Margin" user)
    (46 "B.CrtYd" user "B.Courtyard")
    (47 "F.CrtYd" user "F.Courtyard")
    (48 "B.Fab" user)
    (49 "F.Fab" user)
  )
	(footprint "sa800u-baseboard-hw-footprints:C_0603_1608Metric" (layer "F.Cu")
    (tedit 5D5E94D2)
    (at 82.29 89.92)
    (descr "Capacitor SMD 0603")
    (tags "capacitor 0603")
    (property "Author" "Antmicro")
    (property "Dielectric" "")
    (property "License" "Apache-2.0")
    (property "MPN" "GRM188R60J226MEA0D")
    (property "Manufacturer" "Murata")
    (property "Sheetfile" "psu.kicad_sch")
    (property "Sheetname" "PSU")
    (property "Val" "22u")
    (property "Voltage" "")
    (attr smd)
    (fp_text reference "C141" (at -1.41 -2.3) (layer "F.SilkS")
      (effects (font (size 0.7 0.7) (thickness 0.15)) (justify left bottom))
    )
    (fp_text value "C_22u_0603" (at 0 1.6) (layer "F.Fab")
      (effects (font (size 0.7 0.7) (thickness 0.15)) (justify left bottom))
    )
    (fp_text user "${REFERENCE}" (at -1.682 3.895) (layer "F.Fab") hide
      (effects (font (size 0.7 0.7) (thickness 0.15)) (justify left bottom))
    )
    (fp_text user "License: Apache-2.0" (at -1.682 5.895) (layer "F.Fab") hide
      (effects (font (size 0.7 0.7) (thickness 0.15)) (justify left bottom))
    )
    (fp_text user "Author: Antmicro" (at -1.682 4.894) (layer "F.Fab") hide
      (effects (font (size 0.7 0.7) (thickness 0.15)) (justify left bottom))
    )
    (fp_line (start -0.3 0.3) (end 0.3 0.3) (layer "F.SilkS") (width 0.15))
    (fp_line (start -0.3 -0.3) (end 0.3 -0.3) (layer "F.SilkS") (width 0.15))
    (fp_rect (start -1.24 -0.7) (end 1.24 0.7) (layer "F.CrtYd") (width 0.05) (fill none))
    (fp_rect (start -0.8 -0.4) (end 0.8 0.4) (layer "F.Fab") (width 0.15) (fill none))
    (pad "1" smd roundrect (at -0.7 0) (size 0.6 0.8) (layers "F.Cu" "F.Paste" "F.Mask") (roundrect_rratio 0.2)
      (net 137 "3V8_SYS") (pintype "passive"))
    (pad "2" smd roundrect (at 0.7 0) (size 0.6 0.8) (layers "F.Cu" "F.Paste" "F.Mask") (roundrect_rratio 0.2)
      (net 1 "GND") (pintype "passive"))
  )
	(footprint "sa800u-baseboard-hw-footprints:C_0603_1608Metric" (layer "F.Cu")
    (tedit 5D5E94D2)
    (at 83.52 109.35 90)
    (descr "Capacitor SMD 0603")
    (tags "capacitor 0603")
    (property "Author" "Antmicro")
    (property "Dielectric" "")
    (property "License" "Apache-2.0")
    (property "MPN" "GRM188R60J226MEA0D")
    (property "Manufacturer" "Murata")
    (property "Sheetfile" "psu.kicad_sch")
    (property "Sheetname" "PSU")
    (property "Val" "22u")
    (property "Voltage" "")
    (attr smd)
    (fp_text reference "C139" (at -3.86 0.37 90) (layer "F.SilkS")
      (effects (font (size 0.7 0.7) (thickness 0.15)) (justify left bottom))
    )
    (fp_text value "C_22u_0603" (at 0 1.6 90) (layer "F.Fab")
      (effects (font (size 0.7 0.7) (thickness 0.15)) (justify left bottom))
    )
    (fp_text user "Author: Antmicro" (at -1.682 4.894 90) (layer "F.Fab") hide
      (effects (font (size 0.7 0.7) (thickness 0.15)) (justify left bottom))
    )
    (fp_text user "${REFERENCE}" (at -1.682 3.895 90) (layer "F.Fab") hide
      (effects (font (size 0.7 0.7) (thickness 0.15)) (justify left bottom))
    )
    (fp_text user "License: Apache-2.0" (at -1.682 5.895 90) (layer "F.Fab") hide
      (effects (font (size 0.7 0.7) (thickness 0.15)) (justify left bottom))
    )
    (fp_line (start -0.3 -0.3) (end 0.3 -0.3) (layer "F.SilkS") (width 0.15))
    (fp_line (start -0.3 0.3) (end 0.3 0.3) (layer "F.SilkS") (width 0.15))
    (fp_rect (start -1.24 -0.7) (end 1.24 0.7) (layer "F.CrtYd") (width 0.05) (fill none))
    (fp_rect (start -0.8 -0.4) (end 0.8 0.4) (layer "F.Fab") (width 0.15) (fill none))
    (pad "1" smd roundrect (at -0.7 0 90) (size 0.6 0.8) (layers "F.Cu" "F.Paste" "F.Mask") (roundrect_rratio 0.2)
      (net 131 "3V3_SYS") (pintype "passive"))
    (pad "2" smd roundrect (at 0.7 0 90) (size 0.6 0.8) (layers "F.Cu" "F.Paste" "F.Mask") (roundrect_rratio 0.2)
      (net 1 "GND") (pintype "passive"))
  )
	(footprint "sa800u-baseboard-hw-footprints:SOD-323" (layer "F.Cu")
    (tedit 617A46E7)
    (at 85.6 83.2)
    (property "Author" "Antmicro")
    (property "License" "Apache-2.0")
    (property "MPN" "STS321045B502")
    (property "Manufacturer" "Cooper Bussmann")
    (property "Sheetfile" "som.kicad_sch")
    (property "Sheetname" "SoM")
    (attr smd)
    (fp_text reference "D13" (at -3.43 1.73) (layer "F.SilkS")
      (effects (font (size 0.7 0.7) (thickness 0.15)) (justify left bottom))
    )
    (fp_text value "STS321045B502" (at 0 1.84) (layer "F.Fab")
      (effects (font (size 0.7 0.7) (thickness 0.15)) (justify left bottom))
    )
    (fp_text user "License: Apache-2.0" (at -1.75 6.24) (layer "F.Fab") hide
      (effects (font (size 0.7 0.7) (thickness 0.15)) (justify left bottom))
    )
    (fp_text user "${REFERENCE}" (at -1.75 3.838) (layer "F.Fab") hide
      (effects (font (size 0.7 0.7) (thickness 0.15)) (justify left bottom))
    )
    (fp_text user "Author: Antmicro" (at -1.75 5.038) (layer "F.Fab") hide
      (effects (font (size 0.7 0.7) (thickness 0.15)) (justify left bottom))
    )
    (fp_line (start 0.95 -0.737) (end 0.95 -0.5) (layer "F.SilkS") (width 0.15))
    (fp_line (start -0.95 -0.75) (end -0.95 -0.5005) (layer "F.SilkS") (width 0.15))
    (fp_line (start 0.9505 0.75) (end 0.6495 0.75) (layer "F.SilkS") (width 0.15))
    (fp_line (start 0.625 -0.737) (end 0.95 -0.737) (layer "F.SilkS") (width 0.15))
    (fp_line (start -0.577 0.75) (end -0.95 0.75) (layer "F.SilkS") (width 0.15))
    (fp_line (start 0.9505 0.5) (end 0.9505 0.75) (layer "F.SilkS") (width 0.15))
    (fp_line (start -0.577 -0.75) (end -0.95 -0.75) (layer "F.SilkS") (width 0.15))
    (fp_line (start -0.95 0.5) (end -0.95 0.75) (layer "F.SilkS") (width 0.15))
    (fp_line (start -0.6 -0.5) (end -0.6 0.498) (layer "F.SilkS") (width 0.15))
    (fp_rect (start -1.6 -0.9) (end 1.6 0.9) (layer "F.CrtYd") (width 0.05) (fill none))
    (fp_line (start -0.902 0.699) (end 0.9 0.699) (layer "F.Fab") (width 0.15))
    (fp_line (start 0.9 -0.701) (end -0.902 -0.701) (layer "F.Fab") (width 0.15))
    (fp_line (start 0.9 -0.701) (end 0.9 0.699) (layer "F.Fab") (width 0.15))
    (fp_line (start -0.902 0.699) (end -0.902 -0.701) (layer "F.Fab") (width 0.15))
    (pad "A" smd rect (at 1.124 0) (size 0.8 0.8) (layers "F.Cu" "F.Paste" "F.Mask")
      (net 424 "/SoM/VBAT_SOM") (pinfunction "1") (pintype "unspecified"))
    (pad "K" smd rect (at -1.125 0) (size 0.8 0.8) (layers "F.Cu" "F.Paste" "F.Mask")
      (net 1 "GND") (pinfunction "2") (pintype "unspecified"))
  )
	(footprint "sa800u-baseboard-hw-footprints:L_Coilcraft_XEL4030" (layer "F.Cu")
    (tedit 6215D867)
    (at 78.85 111.7)
    (property "Author" "Antmicro")
    (property "IMax" "")
    (property "ISat" "")
    (property "License" "Apache-2.0")
    (property "MPN" "XEL4030-222MEC")
    (property "Manufacturer" "Coilcraft")
    (property "MaxCur" "6.1A")
    (property "Sheetfile" "psu.kicad_sch")
    (property "Sheetname" "PSU")
    (property "Size" "4x4")
    (property "Val" "2u2/6.1A")
    (attr smd)
    (fp_text reference "L27" (at 0 -2.65) (layer "F.SilkS")
      (effects (font (size 0.7 0.7) (thickness 0.15)) (justify left bottom))
    )
    (fp_text value "L_2u2_6.1A_XEL4030" (at 0 3.35) (layer "F.Fab")
      (effects (font (size 0.7 0.7) (thickness 0.15)) (justify left bottom))
    )
    (fp_text user "Author: Antmicro" (at -2.15 5.996) (layer "F.Fab") hide
      (effects (font (size 0.7 0.7) (thickness 0.15)) (justify left bottom))
    )
    (fp_text user "License: Apache-2.0" (at -2.15 6.996) (layer "F.Fab") hide
      (effects (font (size 0.7 0.7) (thickness 0.15)) (justify left bottom))
    )
    (fp_text user "${REFERENCE}" (at -2.15 4.996) (layer "F.Fab") hide
      (effects (font (size 0.7 0.7) (thickness 0.15)) (justify left bottom))
    )
    (fp_line (start -1.8 2.2) (end 1.85 2.199) (layer "F.SilkS") (width 0.15))
    (fp_line (start -1.8 -2.2) (end 1.85 -2.201) (layer "F.SilkS") (width 0.15))
    (fp_rect (start -2.45 -2.45) (end 2.45 2.45) (layer "F.CrtYd") (width 0.05) (fill none))
    (fp_line (start -2 -2) (end 1.999 -2) (layer "F.Fab") (width 0.15))
    (fp_line (start -2 1.999) (end -2 -2) (layer "F.Fab") (width 0.15))
    (fp_line (start 1.999 1.999) (end -2 1.999) (layer "F.Fab") (width 0.15))
    (fp_line (start 1.999 -2) (end 1.999 1.999) (layer "F.Fab") (width 0.15))
    (pad "1" smd rect (at -1.186 0) (size 0.98 3.4) (layers "F.Cu" "F.Paste" "F.Mask")
      (net 359 "Net-(C133-Pad2)") (pintype "passive"))
    (pad "2" smd rect (at 1.185 0) (size 0.98 3.4) (layers "F.Cu" "F.Paste" "F.Mask")
      (net 131 "3V3_SYS") (pintype "passive"))
  )
	(footprint "sa800u-baseboard-hw-footprints:R_0402_1005Metric" (layer "F.Cu")
    (tedit 5FD9C158)
    (at 72.05 110.35 -90)
    (descr "Resistor SMD 0402")
    (tags "resistor SMD 0402")
    (property "Author" "Antmicro")
    (property "License" "Apache-2.0")
    (property "MPN" "CR0402-FX-3162GLF")
    (property "Manufacturer" "Bourns")
    (property "Sheetfile" "psu.kicad_sch")
    (property "Sheetname" "PSU")
    (property "Tolerance" "1%")
    (property "Val" "31k6")
    (attr smd)
    (fp_text reference "R137" (at 0.27 1.56 -90) (layer "F.SilkS")
      (effects (font (size 0.7 0.7) (thickness 0.15)) (justify left bottom))
    )
    (fp_text value "R_31k6_0402" (at 0 1.4 -90) (layer "F.Fab")
      (effects (font (size 0.7 0.7) (thickness 0.15)) (justify left bottom))
    )
    (fp_text user "Author: Antmicro" (at -0.95 4.169 -90) (layer "F.Fab") hide
      (effects (font (size 0.7 0.7) (thickness 0.15)) (justify left bottom))
    )
    (fp_text user "License: Apache-2.0" (at -0.95 5.169 -90) (layer "F.Fab") hide
      (effects (font (size 0.7 0.7) (thickness 0.15)) (justify left bottom))
    )
    (fp_text user "${REFERENCE}" (at -0.95 3.168 -90) (layer "F.Fab") hide
      (effects (font (size 0.7 0.7) (thickness 0.15)) (justify left bottom))
    )
    (fp_rect (start -0.93 -0.47) (end 0.93 0.47) (layer "F.CrtYd") (width 0.05) (fill none))
    (fp_rect (start -0.5 -0.25) (end 0.5 0.25) (layer "F.Fab") (width 0.15) (fill none))
    (pad "1" smd roundrect (at -0.485 0 270) (size 0.59 0.64) (layers "F.Cu" "F.Paste" "F.Mask") (roundrect_rratio 0.25)
      (net 131 "3V3_SYS") (pintype "passive"))
    (pad "2" smd roundrect (at 0.485 0 270) (size 0.59 0.64) (layers "F.Cu" "F.Paste" "F.Mask") (roundrect_rratio 0.25)
      (net 410 "Net-(R137-Pad2)") (pintype "passive"))
  )
	(footprint "sa800u-baseboard-hw-footprints:R_0402_1005Metric" (layer "F.Cu")
    (tedit 5FD9C158)
    (at 71.05 110.35 90)
    (descr "Resistor SMD 0402")
    (tags "resistor SMD 0402")
    (property "Author" "Antmicro")
    (property "License" "Apache-2.0")
    (property "MPN" "CR0402-FX-1002GLF")
    (property "Manufacturer" "Bourns")
    (property "Sheetfile" "psu.kicad_sch")
    (property "Sheetname" "PSU")
    (property "Tolerance" "1%")
    (property "Val" "10k")
    (attr smd)
    (fp_text reference "R138" (at -0.25 -1.53 90) (layer "F.SilkS")
      (effects (font (size 0.7 0.7) (thickness 0.15)) (justify left bottom))
    )
    (fp_text value "R_10k_0402" (at 0 1.4 90) (layer "F.Fab")
      (effects (font (size 0.7 0.7) (thickness 0.15)) (justify left bottom))
    )
    (fp_text user "License: Apache-2.0" (at -0.95 5.169 90) (layer "F.Fab") hide
      (effects (font (size 0.7 0.7) (thickness 0.15)) (justify left bottom))
    )
    (fp_text user "${REFERENCE}" (at -0.95 3.168 90) (layer "F.Fab") hide
      (effects (font (size 0.7 0.7) (thickness 0.15)) (justify left bottom))
    )
    (fp_text user "Author: Antmicro" (at -0.95 4.169 90) (layer "F.Fab") hide
      (effects (font (size 0.7 0.7) (thickness 0.15)) (justify left bottom))
    )
    (fp_rect (start -0.93 -0.47) (end 0.93 0.47) (layer "F.CrtYd") (width 0.05) (fill none))
    (fp_rect (start -0.5 -0.25) (end 0.5 0.25) (layer "F.Fab") (width 0.15) (fill none))
    (pad "1" smd roundrect (at -0.485 0 90) (size 0.59 0.64) (layers "F.Cu" "F.Paste" "F.Mask") (roundrect_rratio 0.25)
      (net 410 "Net-(R137-Pad2)") (pintype "passive"))
    (pad "2" smd roundrect (at 0.485 0 90) (size 0.59 0.64) (layers "F.Cu" "F.Paste" "F.Mask") (roundrect_rratio 0.25)
      (net 1 "GND") (pintype "passive"))
  )
	(footprint "sa800u-baseboard-hw-footprints:R_0402_1005Metric" (layer "F.Cu")
    (tedit 5FD9C158)
    (at 141.7 143.6 90)
    (descr "Resistor SMD 0402")
    (tags "resistor SMD 0402")
    (property "Author" "Antmicro")
    (property "License" "Apache-2.0")
    (property "MPN" "CR0402-FX-1002GLF")
    (property "Manufacturer" "Bourns")
    (property "Sheetfile" "hdmi-converter.kicad_sch")
    (property "Sheetname" "HDMI converter")
    (property "Tolerance" "1%")
    (property "Val" "10k")
    (attr smd)
    (fp_text reference "R41" (at -1.04 1.38 90) (layer "F.SilkS")
      (effects (font (size 0.7 0.7) (thickness 0.15)) (justify left bottom))
    )
    (fp_text value "R_10k_0402" (at 0 1.4 90) (layer "F.Fab")
      (effects (font (size 0.7 0.7) (thickness 0.15)) (justify left bottom))
    )
    (fp_text user "${REFERENCE}" (at -0.95 3.168 90) (layer "F.Fab") hide
      (effects (font (size 0.7 0.7) (thickness 0.15)) (justify left bottom))
    )
    (fp_text user "Author: Antmicro" (at -0.95 4.169 90) (layer "F.Fab") hide
      (effects (font (size 0.7 0.7) (thickness 0.15)) (justify left bottom))
    )
    (fp_text user "License: Apache-2.0" (at -0.95 5.169 90) (layer "F.Fab") hide
      (effects (font (size 0.7 0.7) (thickness 0.15)) (justify left bottom))
    )
    (fp_rect (start -0.93 -0.47) (end 0.93 0.47) (layer "F.CrtYd") (width 0.05) (fill none))
    (fp_rect (start -0.5 -0.25) (end 0.5 0.25) (layer "F.Fab") (width 0.15) (fill none))
    (pad "1" smd roundrect (at -0.485 0 90) (size 0.59 0.64) (layers "F.Cu" "F.Paste" "F.Mask") (roundrect_rratio 0.25)
      (net 245 "/HDMI converter/5V_HDMI") (pintype "passive"))
    (pad "2" smd roundrect (at 0.485 0 90) (size 0.59 0.64) (layers "F.Cu" "F.Paste" "F.Mask") (roundrect_rratio 0.25)
      (net 1 "GND") (pintype "passive"))
  )
	(footprint "sa800u-baseboard-hw-footprints:R_0402_1005Metric" (layer "F.Cu")
    (tedit 5FD9C158)
    (at 147.8 144)
    (descr "Resistor SMD 0402")
    (tags "resistor SMD 0402")
    (property "Author" "Antmicro")
    (property "License" "Apache-2.0")
    (property "MPN" "CR0402-FX-2002GLF")
    (property "Manufacturer" "Bourns")
    (property "Sheetfile" "hdmi-converter.kicad_sch")
    (property "Sheetname" "HDMI converter")
    (property "Tolerance" "1%")
    (property "Val" "20k")
    (attr smd)
    (fp_text reference "R43" (at 0.83 0.41) (layer "F.SilkS")
      (effects (font (size 0.7 0.7) (thickness 0.15)) (justify left bottom))
    )
    (fp_text value "R_20k_0402" (at 0 1.4) (layer "F.Fab")
      (effects (font (size 0.7 0.7) (thickness 0.15)) (justify left bottom))
    )
    (fp_text user "License: Apache-2.0" (at -0.95 5.169) (layer "F.Fab") hide
      (effects (font (size 0.7 0.7) (thickness 0.15)) (justify left bottom))
    )
    (fp_text user "Author: Antmicro" (at -0.95 4.169) (layer "F.Fab") hide
      (effects (font (size 0.7 0.7) (thickness 0.15)) (justify left bottom))
    )
    (fp_text user "${REFERENCE}" (at -0.95 3.168) (layer "F.Fab") hide
      (effects (font (size 0.7 0.7) (thickness 0.15)) (justify left bottom))
    )
    (fp_rect (start -0.93 -0.47) (end 0.93 0.47) (layer "F.CrtYd") (width 0.05) (fill none))
    (fp_rect (start -0.5 -0.25) (end 0.5 0.25) (layer "F.Fab") (width 0.15) (fill none))
    (pad "1" smd roundrect (at -0.485 0) (size 0.59 0.64) (layers "F.Cu" "F.Paste" "F.Mask") (roundrect_rratio 0.25)
      (net 234 "/HDMI converter/HDMI_DETECT") (pintype "passive"))
    (pad "2" smd roundrect (at 0.485 0) (size 0.59 0.64) (layers "F.Cu" "F.Paste" "F.Mask") (roundrect_rratio 0.25)
      (net 1 "GND") (pintype "passive"))
  )
	(footprint "sa800u-baseboard-hw-footprints:R_0402_1005Metric" (layer "F.Cu")
    (tedit 5FD9C158)
    (at 149.9 107.9 180)
    (descr "Resistor SMD 0402")
    (tags "resistor SMD 0402")
    (property "Author" "Antmicro")
    (property "License" "Apache-2.0")
    (property "MPN" "CR0402-FX-1001GLF")
    (property "Manufacturer" "Bourns")
    (property "Sheetfile" "som.kicad_sch")
    (property "Sheetname" "SoM")
    (property "Tolerance" "1%")
    (property "Val" "1k")
    (attr smd)
    (fp_text reference "R76" (at 1.03 -1.32 180) (layer "F.SilkS")
      (effects (font (size 0.7 0.7) (thickness 0.15)) (justify left bottom))
    )
    (fp_text value "R_1k_0402" (at 0 1.4 180) (layer "F.Fab")
      (effects (font (size 0.7 0.7) (thickness 0.15)) (justify left bottom))
    )
    (fp_text user "Author: Antmicro" (at -0.95 4.169 180) (layer "F.Fab") hide
      (effects (font (size 0.7 0.7) (thickness 0.15)) (justify left bottom))
    )
    (fp_text user "License: Apache-2.0" (at -0.95 5.169 180) (layer "F.Fab") hide
      (effects (font (size 0.7 0.7) (thickness 0.15)) (justify left bottom))
    )
    (fp_text user "${REFERENCE}" (at -0.95 3.168 180) (layer "F.Fab") hide
      (effects (font (size 0.7 0.7) (thickness 0.15)) (justify left bottom))
    )
    (fp_rect (start -0.93 -0.47) (end 0.93 0.47) (layer "F.CrtYd") (width 0.05) (fill none))
    (fp_rect (start -0.5 -0.25) (end 0.5 0.25) (layer "F.Fab") (width 0.15) (fill none))
    (pad "1" smd roundrect (at -0.485 0 180) (size 0.59 0.64) (layers "F.Cu" "F.Paste" "F.Mask") (roundrect_rratio 0.25)
      (net 343 "/SoM/VOL_DOWN_R") (pintype "passive"))
    (pad "2" smd roundrect (at 0.485 0 180) (size 0.59 0.64) (layers "F.Cu" "F.Paste" "F.Mask") (roundrect_rratio 0.25)
      (net 97 "VOL_DOWN") (pintype "passive"))
  )
	(footprint "sa800u-baseboard-hw-footprints:R_0402_1005Metric" (layer "F.Cu")
    (tedit 5FD9C158)
    (at 150.15 95.9 180)
    (descr "Resistor SMD 0402")
    (tags "resistor SMD 0402")
    (property "Author" "Antmicro")
    (property "License" "Apache-2.0")
    (property "MPN" "CR0402-FX-1001GLF")
    (property "Manufacturer" "Bourns")
    (property "Sheetfile" "som.kicad_sch")
    (property "Sheetname" "SoM")
    (property "Tolerance" "1%")
    (property "Val" "1k")
    (attr smd)
    (fp_text reference "R73" (at 2.96 -0.86 180) (layer "F.SilkS")
      (effects (font (size 0.7 0.7) (thickness 0.15)) (justify left bottom))
    )
    (fp_text value "R_1k_0402" (at 0 1.4 180) (layer "F.Fab")
      (effects (font (size 0.7 0.7) (thickness 0.15)) (justify left bottom))
    )
    (fp_text user "${REFERENCE}" (at -0.95 3.168 180) (layer "F.Fab") hide
      (effects (font (size 0.7 0.7) (thickness 0.15)) (justify left bottom))
    )
    (fp_text user "License: Apache-2.0" (at -0.95 5.169 180) (layer "F.Fab") hide
      (effects (font (size 0.7 0.7) (thickness 0.15)) (justify left bottom))
    )
    (fp_text user "Author: Antmicro" (at -0.95 4.169 180) (layer "F.Fab") hide
      (effects (font (size 0.7 0.7) (thickness 0.15)) (justify left bottom))
    )
    (fp_rect (start -0.93 -0.47) (end 0.93 0.47) (layer "F.CrtYd") (width 0.05) (fill none))
    (fp_rect (start -0.5 -0.25) (end 0.5 0.25) (layer "F.Fab") (width 0.15) (fill none))
    (pad "1" smd roundrect (at -0.485 0 180) (size 0.59 0.64) (layers "F.Cu" "F.Paste" "F.Mask") (roundrect_rratio 0.25)
      (net 344 "/SoM/HOME_KEY_R") (pintype "passive"))
    (pad "2" smd roundrect (at 0.485 0 180) (size 0.59 0.64) (layers "F.Cu" "F.Paste" "F.Mask") (roundrect_rratio 0.25)
      (net 94 "HOME_KEY") (pintype "passive"))
  )
)
